(kicad_pcb
	(version 20260206)
	(generator "pcbnew")
	(generator_version "10.0")
	(general
		(thickness 1.6)
		(legacy_teardrops no)
	)
	(paper "A4")
	(title_block
		(title "04192023_DAF0TMB3IC0_F0TG_MB_C_brd_V02_OCP.brd")
		(comment 1 "Grand Teton / footprint 4248 of 8354 (J33), pads 227-291 of 291")
	)
	(layers
		(0 "F.Cu" signal "TOP")
		(4 "In1.Cu" signal "GND")
		(6 "In2.Cu" signal "IN1")
		(8 "In3.Cu" signal "GND1")
		(10 "In4.Cu" signal "IN2")
		(12 "In5.Cu" signal "GND2")
		(14 "In6.Cu" signal "IN3")
		(16 "In7.Cu" signal "GND3")
		(18 "In8.Cu" signal "VCC")
		(20 "In9.Cu" signal "VCC1")
		(22 "In10.Cu" signal "GND4")
		(24 "In11.Cu" signal "IN4")
		(26 "In12.Cu" signal "GND5")
		(28 "In13.Cu" signal "IN5")
		(30 "In14.Cu" signal "GND6")
		(32 "In15.Cu" signal "IN6")
		(34 "In16.Cu" signal "GND7")
		(2 "B.Cu" signal "BOTTOM")
		(9 "F.Adhes" user "F.Adhesive")
		(11 "B.Adhes" user "B.Adhesive")
		(13 "F.Paste" user "Package Geometry/Pastemask Top")
		(15 "B.Paste" user "Package Geometry/Pastemask Bottom")
		(5 "F.SilkS" user "Ref Des/Silkscreen Top")
		(7 "B.SilkS" user "Ref Des/Silkscreen Bottom")
		(1 "F.Mask" user "Board Geometry/Soldermask Top")
		(3 "B.Mask" user "Board Geometry/Soldermask Bottom")
		(17 "Dwgs.User" user "User.Drawings")
		(19 "Cmts.User" user "User.Comments")
		(21 "Eco1.User" user "User.Eco1")
		(23 "Eco2.User" user "User.Eco2")
		(25 "Edge.Cuts" user "Board Geometry/Outline")
		(27 "Margin" user)
		(31 "F.CrtYd" user "Package Geometry/Place Bound Top")
		(29 "B.CrtYd" user "Package Geometry/Place Bound Bottom")
		(35 "F.Fab" user "Ref Des/Assembly Top")
		(33 "B.Fab" user "Ref Des/Assembly Bottom")
	)
	(footprint ""
		(layer "F.Cu")
		(at 19.658076 -255.560322 180)
		(property "Reference" "J33"
			(at -1.25984 -82.079846 0)
			(unlocked yes)
			(layer "F.SilkS")
			(effects
				(font
					(size 0.7874 0.5842)
					(thickness 0.1524)
				)
			)
		)
		(property "Value" ""
			(at 0 0 180)
			(layer "F.Fab")
			(effects
				(font
					(size 1.27 1.27)
				)
			)
		)
		(duplicate_pad_numbers_are_jumpers no)
		(pad "227" smd rect
			(at 2.050034 11.474958 90)
			(size 0.519938 1.4986)
			(layers "F.Cu" "F.Mask" "F.Paste")
			(net "M_F_CPU1_SB_PAR")
		)
		(pad "228" smd rect
			(at 2.050034 12.325096 90)
			(size 0.519938 1.4986)
			(layers "F.Cu" "F.Mask" "F.Paste")
			(net "GND")
		)
		(pad "229" smd rect
			(at 2.050034 13.17498 90)
			(size 0.519938 1.4986)
			(layers "F.Cu" "F.Mask" "F.Paste")
			(net "M_F_CPU1_SB_CS_N<1>")
		)
		(pad "230" smd rect
			(at 2.050034 14.025118 90)
			(size 0.519938 1.4986)
			(layers "F.Cu" "F.Mask" "F.Paste")
			(net "GND")
		)
		(pad "231" smd rect
			(at 2.050034 14.875002 90)
			(size 0.519938 1.4986)
			(layers "F.Cu" "F.Mask" "F.Paste")
			(net "Net_2331")
		)
		(pad "232" smd rect
			(at 2.050034 15.724886 90)
			(size 0.519938 1.4986)
			(layers "F.Cu" "F.Mask" "F.Paste")
			(net "Net_2332")
		)
		(pad "233" smd rect
			(at 2.050034 16.575024 90)
			(size 0.519938 1.4986)
			(layers "F.Cu" "F.Mask" "F.Paste")
			(net "GND")
		)
		(pad "234" smd rect
			(at 2.050034 17.424908 90)
			(size 0.519938 1.4986)
			(layers "F.Cu" "F.Mask" "F.Paste")
			(net "M_F_CPU1_SB_CB<6>")
		)
		(pad "235" smd rect
			(at 2.050034 18.275046 90)
			(size 0.519938 1.4986)
			(layers "F.Cu" "F.Mask" "F.Paste")
			(net "GND")
		)
		(pad "236" smd rect
			(at 2.050034 19.12493 90)
			(size 0.519938 1.4986)
			(layers "F.Cu" "F.Mask" "F.Paste")
			(net "M_F_CPU1_SB_CB<7>")
		)
		(pad "237" smd rect
			(at 2.050034 19.975068 90)
			(size 0.519938 1.4986)
			(layers "F.Cu" "F.Mask" "F.Paste")
			(net "GND")
		)
		(pad "238" smd rect
			(at 2.050034 20.824952 90)
			(size 0.519938 1.4986)
			(layers "F.Cu" "F.Mask" "F.Paste")
			(net "M_F_CPU1_SB_DQS_DN<4>")
		)
		(pad "239" smd rect
			(at 2.050034 21.67509 90)
			(size 0.519938 1.4986)
			(layers "F.Cu" "F.Mask" "F.Paste")
			(net "M_F_CPU1_SB_DQS_DP<4>")
		)
		(pad "240" smd rect
			(at 2.050034 22.524974 90)
			(size 0.519938 1.4986)
			(layers "F.Cu" "F.Mask" "F.Paste")
			(net "GND")
		)
		(pad "241" smd rect
			(at 2.050034 23.375112 90)
			(size 0.519938 1.4986)
			(layers "F.Cu" "F.Mask" "F.Paste")
			(net "M_F_CPU1_SB_CB<2>")
		)
		(pad "242" smd rect
			(at 2.050034 24.224996 90)
			(size 0.519938 1.4986)
			(layers "F.Cu" "F.Mask" "F.Paste")
			(net "GND")
		)
		(pad "243" smd rect
			(at 2.050034 25.07488 90)
			(size 0.519938 1.4986)
			(layers "F.Cu" "F.Mask" "F.Paste")
			(net "M_F_CPU1_SB_CB<3>")
		)
		(pad "244" smd rect
			(at 2.050034 25.925018 90)
			(size 0.519938 1.4986)
			(layers "F.Cu" "F.Mask" "F.Paste")
			(net "GND")
		)
		(pad "245" smd rect
			(at 2.050034 26.774902 90)
			(size 0.519938 1.4986)
			(layers "F.Cu" "F.Mask" "F.Paste")
			(net "M_F_CPU1_SB_DQ<2>")
		)
		(pad "246" smd rect
			(at 2.050034 27.62504 90)
			(size 0.519938 1.4986)
			(layers "F.Cu" "F.Mask" "F.Paste")
			(net "GND")
		)
		(pad "247" smd rect
			(at 2.050034 28.474924 90)
			(size 0.519938 1.4986)
			(layers "F.Cu" "F.Mask" "F.Paste")
			(net "M_F_CPU1_SB_DQ<3>")
		)
		(pad "248" smd rect
			(at 2.050034 29.325062 90)
			(size 0.519938 1.4986)
			(layers "F.Cu" "F.Mask" "F.Paste")
			(net "GND")
		)
		(pad "249" smd rect
			(at 2.050034 30.174946 90)
			(size 0.519938 1.4986)
			(layers "F.Cu" "F.Mask" "F.Paste")
			(net "M_F_CPU1_SB_DQS_DN<5>")
		)
		(pad "250" smd rect
			(at 2.050034 31.025084 90)
			(size 0.519938 1.4986)
			(layers "F.Cu" "F.Mask" "F.Paste")
			(net "M_F_CPU1_SB_DQS_DP<5>")
		)
		(pad "251" smd rect
			(at 2.050034 31.874968 90)
			(size 0.519938 1.4986)
			(layers "F.Cu" "F.Mask" "F.Paste")
			(net "GND")
		)
		(pad "252" smd rect
			(at 2.050034 32.725106 90)
			(size 0.519938 1.4986)
			(layers "F.Cu" "F.Mask" "F.Paste")
			(net "M_F_CPU1_SB_DQ<6>")
		)
		(pad "253" smd rect
			(at 2.050034 33.57499 90)
			(size 0.519938 1.4986)
			(layers "F.Cu" "F.Mask" "F.Paste")
			(net "GND")
		)
		(pad "254" smd rect
			(at 2.050034 34.425128 90)
			(size 0.519938 1.4986)
			(layers "F.Cu" "F.Mask" "F.Paste")
			(net "M_F_CPU1_SB_DQ<7>")
		)
		(pad "255" smd rect
			(at 2.050034 35.275012 90)
			(size 0.519938 1.4986)
			(layers "F.Cu" "F.Mask" "F.Paste")
			(net "GND")
		)
		(pad "256" smd rect
			(at 2.050034 36.124896 90)
			(size 0.519938 1.4986)
			(layers "F.Cu" "F.Mask" "F.Paste")
			(net "M_F_CPU1_SB_DQ<10>")
		)
		(pad "257" smd rect
			(at 2.050034 36.975034 90)
			(size 0.519938 1.4986)
			(layers "F.Cu" "F.Mask" "F.Paste")
			(net "GND")
		)
		(pad "258" smd rect
			(at 2.050034 37.824918 90)
			(size 0.519938 1.4986)
			(layers "F.Cu" "F.Mask" "F.Paste")
			(net "M_F_CPU1_SB_DQ<11>")
		)
		(pad "259" smd rect
			(at 2.050034 38.675056 90)
			(size 0.519938 1.4986)
			(layers "F.Cu" "F.Mask" "F.Paste")
			(net "GND")
		)
		(pad "260" smd rect
			(at 2.050034 39.52494 90)
			(size 0.519938 1.4986)
			(layers "F.Cu" "F.Mask" "F.Paste")
			(net "M_F_CPU1_SB_DQS_DN<6>")
		)
		(pad "261" smd rect
			(at 2.050034 40.375078 90)
			(size 0.519938 1.4986)
			(layers "F.Cu" "F.Mask" "F.Paste")
			(net "M_F_CPU1_SB_DQS_DP<6>")
		)
		(pad "262" smd rect
			(at 2.050034 41.224962 90)
			(size 0.519938 1.4986)
			(layers "F.Cu" "F.Mask" "F.Paste")
			(net "GND")
		)
		(pad "263" smd rect
			(at 2.050034 42.0751 90)
			(size 0.519938 1.4986)
			(layers "F.Cu" "F.Mask" "F.Paste")
			(net "M_F_CPU1_SB_DQ<14>")
		)
		(pad "264" smd rect
			(at 2.050034 42.924984 90)
			(size 0.519938 1.4986)
			(layers "F.Cu" "F.Mask" "F.Paste")
			(net "GND")
		)
		(pad "265" smd rect
			(at 2.050034 43.775122 90)
			(size 0.519938 1.4986)
			(layers "F.Cu" "F.Mask" "F.Paste")
			(net "M_F_CPU1_SB_DQ<15>")
		)
		(pad "266" smd rect
			(at 2.050034 44.625006 90)
			(size 0.519938 1.4986)
			(layers "F.Cu" "F.Mask" "F.Paste")
			(net "GND")
		)
		(pad "267" smd rect
			(at 2.050034 45.47489 90)
			(size 0.519938 1.4986)
			(layers "F.Cu" "F.Mask" "F.Paste")
			(net "M_F_CPU1_SB_DQ<18>")
		)
		(pad "268" smd rect
			(at 2.050034 46.325028 90)
			(size 0.519938 1.4986)
			(layers "F.Cu" "F.Mask" "F.Paste")
			(net "GND")
		)
		(pad "269" smd rect
			(at 2.050034 47.174912 90)
			(size 0.519938 1.4986)
			(layers "F.Cu" "F.Mask" "F.Paste")
			(net "M_F_CPU1_SB_DQ<19>")
		)
		(pad "270" smd rect
			(at 2.050034 48.02505 90)
			(size 0.519938 1.4986)
			(layers "F.Cu" "F.Mask" "F.Paste")
			(net "GND")
		)
		(pad "271" smd rect
			(at 2.050034 48.874934 90)
			(size 0.519938 1.4986)
			(layers "F.Cu" "F.Mask" "F.Paste")
			(net "M_F_CPU1_SB_DQS_DN<7>")
		)
		(pad "272" smd rect
			(at 2.050034 49.725072 90)
			(size 0.519938 1.4986)
			(layers "F.Cu" "F.Mask" "F.Paste")
			(net "M_F_CPU1_SB_DQS_DP<7>")
		)
		(pad "273" smd rect
			(at 2.050034 50.574956 90)
			(size 0.519938 1.4986)
			(layers "F.Cu" "F.Mask" "F.Paste")
			(net "GND")
		)
		(pad "274" smd rect
			(at 2.050034 51.425094 90)
			(size 0.519938 1.4986)
			(layers "F.Cu" "F.Mask" "F.Paste")
			(net "M_F_CPU1_SB_DQ<22>")
		)
		(pad "275" smd rect
			(at 2.050034 52.274978 90)
			(size 0.519938 1.4986)
			(layers "F.Cu" "F.Mask" "F.Paste")
			(net "GND")
		)
		(pad "276" smd rect
			(at 2.050034 53.125116 90)
			(size 0.519938 1.4986)
			(layers "F.Cu" "F.Mask" "F.Paste")
			(net "M_F_CPU1_SB_DQ<23>")
		)
		(pad "277" smd rect
			(at 2.050034 53.975 90)
			(size 0.519938 1.4986)
			(layers "F.Cu" "F.Mask" "F.Paste")
			(net "GND")
		)
		(pad "278" smd rect
			(at 2.050034 54.824884 90)
			(size 0.519938 1.4986)
			(layers "F.Cu" "F.Mask" "F.Paste")
			(net "M_F_CPU1_SB_DQ<26>")
		)
		(pad "279" smd rect
			(at 2.050034 55.675022 90)
			(size 0.519938 1.4986)
			(layers "F.Cu" "F.Mask" "F.Paste")
			(net "GND")
		)
		(pad "280" smd rect
			(at 2.050034 56.524906 90)
			(size 0.519938 1.4986)
			(layers "F.Cu" "F.Mask" "F.Paste")
			(net "M_F_CPU1_SB_DQ<27>")
		)
		(pad "281" smd rect
			(at 2.050034 57.375044 90)
			(size 0.519938 1.4986)
			(layers "F.Cu" "F.Mask" "F.Paste")
			(net "GND")
		)
		(pad "282" smd rect
			(at 2.050034 58.224928 90)
			(size 0.519938 1.4986)
			(layers "F.Cu" "F.Mask" "F.Paste")
			(net "M_F_CPU1_SB_DQS_DN<8>")
		)
		(pad "283" smd rect
			(at 2.050034 59.075066 90)
			(size 0.519938 1.4986)
			(layers "F.Cu" "F.Mask" "F.Paste")
			(net "M_F_CPU1_SB_DQS_DP<8>")
		)
		(pad "284" smd rect
			(at 2.050034 59.92495 90)
			(size 0.519938 1.4986)
			(layers "F.Cu" "F.Mask" "F.Paste")
			(net "GND")
		)
		(pad "285" smd rect
			(at 2.050034 60.775088 90)
			(size 0.519938 1.4986)
			(layers "F.Cu" "F.Mask" "F.Paste")
			(net "M_F_CPU1_SB_DQ<30>")
		)
		(pad "286" smd rect
			(at 2.050034 61.624972 90)
			(size 0.519938 1.4986)
			(layers "F.Cu" "F.Mask" "F.Paste")
			(net "GND")
		)
		(pad "287" smd rect
			(at 2.050034 62.47511 90)
			(size 0.519938 1.4986)
			(layers "F.Cu" "F.Mask" "F.Paste")
			(net "M_F_CPU1_SB_DQ<31>")
		)
		(pad "288" smd rect
			(at 2.050034 63.324994 90)
			(size 0.519938 1.4986)
			(layers "F.Cu" "F.Mask" "F.Paste")
			(net "GND")
		)
		(pad "G1" thru_hole oval
			(at 0 -68.97497 90)
			(size 1.7272 3.4798)
			(drill oval 1.2192 2.4638)
			(layers "*.Cu" "*.Mask")
			(remove_unused_layers no)
			(net "GND")
			(clearance 0.127)
			(thermal_gap 0.127)
		)
		(pad "G2" thru_hole oval
			(at 0 3.875024 90)
			(size 1.7272 3.4798)
			(drill oval 1.2192 2.4638)
			(layers "*.Cu" "*.Mask")
			(remove_unused_layers no)
			(net "GND")
			(clearance 0.127)
			(thermal_gap 0.127)
		)
		(pad "G3" thru_hole oval
			(at 0 68.97497 90)
			(size 1.7272 3.4798)
			(drill oval 1.2192 2.4638)
			(layers "*.Cu" "*.Mask")
			(remove_unused_layers no)
			(net "GND")
			(clearance 0.127)
			(thermal_gap 0.127)
		)
	)
)
